(kicad_pcb
	(version 20260206)
	(generator "pcbnew")
	(generator_version "10.0")
	(general
		(thickness 1.6)
		(legacy_teardrops no)
	)
	(paper "A4")
	(title_block
		(title "Bryce Canyon_SCC_16316-1_OCP.brd")
		(comment 1 "Bryce Canyon / footprints 147-154 of 1561")
	)
	(layers
		(0 "F.Cu" signal "TOP")
		(4 "In1.Cu" signal "L2GND")
		(6 "In2.Cu" signal "L3")
		(8 "In3.Cu" signal "L4VCC")
		(10 "In4.Cu" signal "L5VCC")
		(12 "In5.Cu" signal "L6")
		(14 "In6.Cu" signal "L7GND")
		(2 "B.Cu" signal "BOTTOM")
		(9 "F.Adhes" user "F.Adhesive")
		(11 "B.Adhes" user "B.Adhesive")
		(13 "F.Paste" user "Package Geometry/Pastemask Top")
		(15 "B.Paste" user "Package Geometry/Pastemask Bottom")
		(5 "F.SilkS" user "Ref Des/Silkscreen Top")
		(7 "B.SilkS" user "Ref Des/Silkscreen Bottom")
		(1 "F.Mask" user "Board Geometry/Soldermask Top")
		(3 "B.Mask" user "Board Geometry/Soldermask Bottom")
		(17 "Dwgs.User" user "User.Drawings")
		(19 "Cmts.User" user "User.Comments")
		(21 "Eco1.User" user "User.Eco1")
		(23 "Eco2.User" user "User.Eco2")
		(25 "Edge.Cuts" user "Board Geometry/Outline")
		(27 "Margin" user)
		(31 "F.CrtYd" user "Package Geometry/Place Bound Top")
		(29 "B.CrtYd" user "Package Geometry/Place Bound Bottom")
		(35 "F.Fab" user "Ref Des/Assembly Top")
		(33 "B.Fab" user "Ref Des/Assembly Bottom")
	)
	(footprint ""
		(layer "F.Cu")
		(at 176.6824 -59.817 180)
		(property "Reference" "R269"
			(at 0 0 180)
			(layer "F.SilkS")
			(hide yes)
			(effects
				(font
					(size 1.27 1.27)
				)
			)
		)
		(property "Value" "10KR2F-2-GP"
			(at 0.064008 -3.993896 180)
			(unlocked yes)
			(layer "F.Fab")
			(hide yes)
			(effects
				(font
					(size 1.016 1.016)
					(thickness 0.1524)
				)
			)
		)
		(property "Device Type" "R402H16"
			(at 0.064008 -5.517896 180)
			(unlocked yes)
			(layer "F.Fab")
			(hide yes)
			(effects
				(font
					(size 1.016 1.016)
					(thickness 0.1524)
				)
			)
		)
		(duplicate_pad_numbers_are_jumpers no)
		(fp_line
			(start 0.508 -0.9398)
			(end -0.508 -0.9398)
			(stroke
				(width 0.1524)
				(type default)
			)
			(layer "F.SilkS")
		)
		(fp_line
			(start -0.508 -0.9398)
			(end -0.508 0.9398)
			(stroke
				(width 0.1524)
				(type default)
			)
			(layer "F.SilkS")
		)
		(fp_rect
			(start -0.508 0.9398)
			(end 0.508 -0.9398)
			(stroke
				(width 0)
				(type default)
			)
			(fill no)
			(layer "F.CrtYd")
		)
		(fp_rect
			(start -0.508 0.9398)
			(end 0.508 -0.9398)
			(stroke
				(width 0)
				(type default)
			)
			(fill no)
			(layer "F.Fab")
		)
		(pad "1" smd custom
			(at 0 -0.4445 180)
			(size 0.1397 0.1397)
			(layers "F.Cu" "F.Mask" "F.Paste")
			(net "LSI_SCAN_EN")
			(options
				(clearance outline)
				(anchor circle)
			)
			(primitives
				(gr_poly
					(pts
						(arc
							(start -0.1778 -0.2794)
							(mid -0.249642 -0.249642)
							(end -0.2794 -0.1778)
						)
						(arc
							(start -0.2794 0.1778)
							(mid -0.249642 0.249642)
							(end -0.1778 0.2794)
						)
						(arc
							(start 0.1778 0.2794)
							(mid 0.249642 0.249642)
							(end 0.2794 0.1778)
						)
						(arc
							(start 0.2794 -0.1778)
							(mid 0.249642 -0.249642)
							(end 0.1778 -0.2794)
						)
					)
					(width 0)
					(fill yes)
				)
			)
		)
		(pad "2" smd custom
			(at 0 0.4445 180)
			(size 0.1397 0.1397)
			(layers "F.Cu" "F.Mask" "F.Paste")
			(net "GND")
			(options
				(clearance outline)
				(anchor circle)
			)
			(primitives
				(gr_poly
					(pts
						(arc
							(start -0.1778 -0.2794)
							(mid -0.249642 -0.249642)
							(end -0.2794 -0.1778)
						)
						(arc
							(start -0.2794 0.1778)
							(mid -0.249642 0.249642)
							(end -0.1778 0.2794)
						)
						(arc
							(start 0.1778 0.2794)
							(mid 0.249642 0.249642)
							(end 0.2794 0.1778)
						)
						(arc
							(start 0.2794 -0.1778)
							(mid 0.249642 -0.249642)
							(end 0.1778 -0.2794)
						)
					)
					(width 0)
					(fill yes)
				)
			)
		)
	)
	(footprint ""
		(layer "F.Cu")
		(at 92.208858 -79.414116 -90)
		(property "Reference" "R130"
			(at 0 0 270)
			(layer "F.SilkS")
			(hide yes)
			(effects
				(font
					(size 1.27 1.27)
				)
			)
		)
		(property "Value" "4K7R2F-GP"
			(at 0.064008 -3.993896 270)
			(unlocked yes)
			(layer "F.Fab")
			(hide yes)
			(effects
				(font
					(size 1.016 1.016)
					(thickness 0.1524)
				)
			)
		)
		(property "Device Type" "R402H16"
			(at 0.064008 -5.517896 270)
			(unlocked yes)
			(layer "F.Fab")
			(hide yes)
			(effects
				(font
					(size 1.016 1.016)
					(thickness 0.1524)
				)
			)
		)
		(duplicate_pad_numbers_are_jumpers no)
		(fp_line
			(start -0.508 -0.9398)
			(end -0.508 0.9398)
			(stroke
				(width 0.1524)
				(type default)
			)
			(layer "F.SilkS")
		)
		(fp_line
			(start 0.508 -0.9398)
			(end -0.508 -0.9398)
			(stroke
				(width 0.1524)
				(type default)
			)
			(layer "F.SilkS")
		)
		(fp_rect
			(start -0.508 0.9398)
			(end 0.508 -0.9398)
			(stroke
				(width 0)
				(type default)
			)
			(fill no)
			(layer "F.CrtYd")
		)
		(fp_rect
			(start -0.508 0.9398)
			(end 0.508 -0.9398)
			(stroke
				(width 0)
				(type default)
			)
			(fill no)
			(layer "F.Fab")
		)
		(pad "1" smd custom
			(at 0 -0.4445 270)
			(size 0.1397 0.1397)
			(layers "F.Cu" "F.Mask" "F.Paste")
			(net "P1V8_E")
			(options
				(clearance outline)
				(anchor circle)
			)
			(primitives
				(gr_poly
					(pts
						(arc
							(start -0.1778 -0.2794)
							(mid -0.249642 -0.249642)
							(end -0.2794 -0.1778)
						)
						(arc
							(start -0.2794 0.1778)
							(mid -0.249642 0.249642)
							(end -0.1778 0.2794)
						)
						(arc
							(start 0.1778 0.2794)
							(mid 0.249642 0.249642)
							(end 0.2794 0.1778)
						)
						(arc
							(start 0.2794 -0.1778)
							(mid 0.249642 -0.249642)
							(end 0.1778 -0.2794)
						)
					)
					(width 0)
					(fill yes)
				)
			)
		)
		(pad "2" smd custom
			(at 0 0.4445 270)
			(size 0.1397 0.1397)
			(layers "F.Cu" "F.Mask" "F.Paste")
			(net "EXP_RESET_N")
			(options
				(clearance outline)
				(anchor circle)
			)
			(primitives
				(gr_poly
					(pts
						(arc
							(start -0.1778 -0.2794)
							(mid -0.249642 -0.249642)
							(end -0.2794 -0.1778)
						)
						(arc
							(start -0.2794 0.1778)
							(mid -0.249642 0.249642)
							(end -0.1778 0.2794)
						)
						(arc
							(start 0.1778 0.2794)
							(mid 0.249642 0.249642)
							(end 0.2794 0.1778)
						)
						(arc
							(start 0.2794 -0.1778)
							(mid 0.249642 -0.249642)
							(end 0.1778 -0.2794)
						)
					)
					(width 0)
					(fill yes)
				)
			)
		)
	)
	(footprint ""
		(layer "F.Cu")
		(at 127.076708 -46.415706 90)
		(property "Reference" "VIA10"
			(at 0 0 90)
			(layer "F.SilkS")
			(hide yes)
			(effects
				(font
					(size 1.27 1.27)
				)
			)
		)
		(property "Value" "100OHM-8L-1D6MM-L13-GP"
			(at 3.2893 0.0508 90)
			(unlocked yes)
			(layer "F.Fab")
			(hide yes)
			(effects
				(font
					(size 1.016 1.016)
					(thickness 0.1524)
				)
			)
		)
		(property "Device Type" "VIA-PCIE-4P-409091"
			(at 3.2893 -1.4732 90)
			(unlocked yes)
			(layer "F.Fab")
			(hide yes)
			(effects
				(font
					(size 1.016 1.016)
					(thickness 0.1524)
				)
			)
		)
		(duplicate_pad_numbers_are_jumpers no)
		(fp_rect
			(start -2.0447 0.4572)
			(end 2.0447 -0.4572)
			(stroke
				(width 0)
				(type default)
			)
			(fill no)
			(layer "F.CrtYd")
		)
		(fp_rect
			(start -2.0447 0.4572)
			(end 2.0447 -0.4572)
			(stroke
				(width 0)
				(type default)
			)
			(fill no)
			(layer "F.Fab")
		)
		(pad "1" thru_hole circle
			(at -1.5875 0 90)
			(size 0.508 0.508)
			(drill 0.254)
			(layers "*.Cu" "*.Mask")
			(remove_unused_layers no)
			(net "GND")
			(clearance 0.2032)
			(thermal_gap 0.2032)
		)
		(pad "2" thru_hole circle
			(at -0.5715 0 90)
			(size 0.508 0.508)
			(drill 0.254)
			(layers "*.Cu" "*.Mask")
			(remove_unused_layers no)
			(net "PHY_IOC_TO_SCC_C_41_DP")
			(clearance 0.2032)
			(thermal_gap 0.2032)
		)
		(pad "3" thru_hole circle
			(at 0.5715 0 90)
			(size 0.508 0.508)
			(drill 0.254)
			(layers "*.Cu" "*.Mask")
			(remove_unused_layers no)
			(net "PHY_IOC_TO_SCC_C_41_DN")
			(clearance 0.2032)
			(thermal_gap 0.2032)
		)
		(pad "4" thru_hole circle
			(at 1.5875 0 90)
			(size 0.508 0.508)
			(drill 0.254)
			(layers "*.Cu" "*.Mask")
			(remove_unused_layers no)
			(net "GND")
			(clearance 0.2032)
			(thermal_gap 0.2032)
		)
	)
	(footprint ""
		(layer "F.Cu")
		(at 191.039242 -37.65423 -90)
		(property "Reference" "R254"
			(at 0 0 270)
			(layer "F.SilkS")
			(hide yes)
			(effects
				(font
					(size 1.27 1.27)
				)
			)
		)
		(property "Value" "10KR2F-2-GP"
			(at 0.064008 -3.993896 270)
			(unlocked yes)
			(layer "F.Fab")
			(hide yes)
			(effects
				(font
					(size 1.016 1.016)
					(thickness 0.1524)
				)
			)
		)
		(property "Device Type" "R402H16"
			(at 0.064008 -5.517896 270)
			(unlocked yes)
			(layer "F.Fab")
			(hide yes)
			(effects
				(font
					(size 1.016 1.016)
					(thickness 0.1524)
				)
			)
		)
		(duplicate_pad_numbers_are_jumpers no)
		(fp_line
			(start -0.508 -0.9398)
			(end -0.508 0.9398)
			(stroke
				(width 0.1524)
				(type default)
			)
			(layer "F.SilkS")
		)
		(fp_line
			(start 0.508 -0.9398)
			(end -0.508 -0.9398)
			(stroke
				(width 0.1524)
				(type default)
			)
			(layer "F.SilkS")
		)
		(fp_rect
			(start -0.508 0.9398)
			(end 0.508 -0.9398)
			(stroke
				(width 0)
				(type default)
			)
			(fill no)
			(layer "F.CrtYd")
		)
		(fp_rect
			(start -0.508 0.9398)
			(end 0.508 -0.9398)
			(stroke
				(width 0)
				(type default)
			)
			(fill no)
			(layer "F.Fab")
		)
		(pad "1" smd custom
			(at 0 -0.4445 270)
			(size 0.1397 0.1397)
			(layers "F.Cu" "F.Mask" "F.Paste")
			(net "P1V8_C")
			(options
				(clearance outline)
				(anchor circle)
			)
			(primitives
				(gr_poly
					(pts
						(arc
							(start -0.1778 -0.2794)
							(mid -0.249642 -0.249642)
							(end -0.2794 -0.1778)
						)
						(arc
							(start -0.2794 0.1778)
							(mid -0.249642 0.249642)
							(end -0.1778 0.2794)
						)
						(arc
							(start 0.1778 0.2794)
							(mid 0.249642 0.249642)
							(end 0.2794 0.1778)
						)
						(arc
							(start 0.2794 -0.1778)
							(mid 0.249642 -0.249642)
							(end 0.1778 -0.2794)
						)
					)
					(width 0)
					(fill yes)
				)
			)
		)
		(pad "2" smd custom
			(at 0 0.4445 270)
			(size 0.1397 0.1397)
			(layers "F.Cu" "F.Mask" "F.Paste")
			(net "CP_DONE")
			(options
				(clearance outline)
				(anchor circle)
			)
			(primitives
				(gr_poly
					(pts
						(arc
							(start -0.1778 -0.2794)
							(mid -0.249642 -0.249642)
							(end -0.2794 -0.1778)
						)
						(arc
							(start -0.2794 0.1778)
							(mid -0.249642 0.249642)
							(end -0.1778 0.2794)
						)
						(arc
							(start 0.1778 0.2794)
							(mid 0.249642 0.249642)
							(end 0.2794 0.1778)
						)
						(arc
							(start 0.2794 -0.1778)
							(mid 0.249642 -0.249642)
							(end 0.1778 -0.2794)
						)
					)
					(width 0)
					(fill yes)
				)
			)
		)
	)
	(footprint ""
		(layer "F.Cu")
		(at 7.5946 -94.831408 180)
		(property "Reference" "R412"
			(at 0 0 180)
			(layer "F.SilkS")
			(hide yes)
			(effects
				(font
					(size 1.27 1.27)
				)
			)
		)
		(property "Value" "200KR2F-L-GP"
			(at 0.064008 -3.993896 180)
			(unlocked yes)
			(layer "F.Fab")
			(hide yes)
			(effects
				(font
					(size 1.016 1.016)
					(thickness 0.1524)
				)
			)
		)
		(property "Device Type" "R402H16"
			(at 0.064008 -5.517896 180)
			(unlocked yes)
			(layer "F.Fab")
			(hide yes)
			(effects
				(font
					(size 1.016 1.016)
					(thickness 0.1524)
				)
			)
		)
		(duplicate_pad_numbers_are_jumpers no)
		(fp_line
			(start 0.508 -0.9398)
			(end -0.508 -0.9398)
			(stroke
				(width 0.1524)
				(type default)
			)
			(layer "F.SilkS")
		)
		(fp_line
			(start -0.508 -0.9398)
			(end -0.508 0.9398)
			(stroke
				(width 0.1524)
				(type default)
			)
			(layer "F.SilkS")
		)
		(fp_rect
			(start -0.508 0.9398)
			(end 0.508 -0.9398)
			(stroke
				(width 0)
				(type default)
			)
			(fill no)
			(layer "F.CrtYd")
		)
		(fp_rect
			(start -0.508 0.9398)
			(end 0.508 -0.9398)
			(stroke
				(width 0)
				(type default)
			)
			(fill no)
			(layer "F.Fab")
		)
		(pad "1" smd custom
			(at 0 -0.4445 180)
			(size 0.1397 0.1397)
			(layers "F.Cu" "F.Mask" "F.Paste")
			(net "VREF2")
			(options
				(clearance outline)
				(anchor circle)
			)
			(primitives
				(gr_poly
					(pts
						(arc
							(start -0.1778 -0.2794)
							(mid -0.249642 -0.249642)
							(end -0.2794 -0.1778)
						)
						(arc
							(start -0.2794 0.1778)
							(mid -0.249642 0.249642)
							(end -0.1778 0.2794)
						)
						(arc
							(start 0.1778 0.2794)
							(mid 0.249642 0.249642)
							(end 0.2794 0.1778)
						)
						(arc
							(start 0.2794 -0.1778)
							(mid 0.249642 -0.249642)
							(end 0.1778 -0.2794)
						)
					)
					(width 0)
					(fill yes)
				)
			)
		)
		(pad "2" smd custom
			(at 0 0.4445 180)
			(size 0.1397 0.1397)
			(layers "F.Cu" "F.Mask" "F.Paste")
			(net "P3V3")
			(options
				(clearance outline)
				(anchor circle)
			)
			(primitives
				(gr_poly
					(pts
						(arc
							(start -0.1778 -0.2794)
							(mid -0.249642 -0.249642)
							(end -0.2794 -0.1778)
						)
						(arc
							(start -0.2794 0.1778)
							(mid -0.249642 0.249642)
							(end -0.1778 0.2794)
						)
						(arc
							(start 0.1778 0.2794)
							(mid 0.249642 0.249642)
							(end 0.2794 0.1778)
						)
						(arc
							(start 0.2794 -0.1778)
							(mid 0.249642 -0.249642)
							(end 0.1778 -0.2794)
						)
					)
					(width 0)
					(fill yes)
				)
			)
		)
	)
	(footprint ""
		(layer "F.Cu")
		(at 177.6984 -59.817 180)
		(property "Reference" "R274"
			(at 0 0 180)
			(layer "F.SilkS")
			(hide yes)
			(effects
				(font
					(size 1.27 1.27)
				)
			)
		)
		(property "Value" "10KR2F-2-GP"
			(at 0.064008 -3.993896 180)
			(unlocked yes)
			(layer "F.Fab")
			(hide yes)
			(effects
				(font
					(size 1.016 1.016)
					(thickness 0.1524)
				)
			)
		)
		(property "Device Type" "R402H16"
			(at 0.064008 -5.517896 180)
			(unlocked yes)
			(layer "F.Fab")
			(hide yes)
			(effects
				(font
					(size 1.016 1.016)
					(thickness 0.1524)
				)
			)
		)
		(duplicate_pad_numbers_are_jumpers no)
		(fp_line
			(start 0.508 -0.9398)
			(end -0.508 -0.9398)
			(stroke
				(width 0.1524)
				(type default)
			)
			(layer "F.SilkS")
		)
		(fp_line
			(start -0.508 -0.9398)
			(end -0.508 0.9398)
			(stroke
				(width 0.1524)
				(type default)
			)
			(layer "F.SilkS")
		)
		(fp_rect
			(start -0.508 0.9398)
			(end 0.508 -0.9398)
			(stroke
				(width 0)
				(type default)
			)
			(fill no)
			(layer "F.CrtYd")
		)
		(fp_rect
			(start -0.508 0.9398)
			(end 0.508 -0.9398)
			(stroke
				(width 0)
				(type default)
			)
			(fill no)
			(layer "F.Fab")
		)
		(pad "1" smd custom
			(at 0 -0.4445 180)
			(size 0.1397 0.1397)
			(layers "F.Cu" "F.Mask" "F.Paste")
			(net "LSI_IDDT")
			(options
				(clearance outline)
				(anchor circle)
			)
			(primitives
				(gr_poly
					(pts
						(arc
							(start -0.1778 -0.2794)
							(mid -0.249642 -0.249642)
							(end -0.2794 -0.1778)
						)
						(arc
							(start -0.2794 0.1778)
							(mid -0.249642 0.249642)
							(end -0.1778 0.2794)
						)
						(arc
							(start 0.1778 0.2794)
							(mid 0.249642 0.249642)
							(end 0.2794 0.1778)
						)
						(arc
							(start 0.2794 -0.1778)
							(mid 0.249642 -0.249642)
							(end 0.1778 -0.2794)
						)
					)
					(width 0)
					(fill yes)
				)
			)
		)
		(pad "2" smd custom
			(at 0 0.4445 180)
			(size 0.1397 0.1397)
			(layers "F.Cu" "F.Mask" "F.Paste")
			(net "GND")
			(options
				(clearance outline)
				(anchor circle)
			)
			(primitives
				(gr_poly
					(pts
						(arc
							(start -0.1778 -0.2794)
							(mid -0.249642 -0.249642)
							(end -0.2794 -0.1778)
						)
						(arc
							(start -0.2794 0.1778)
							(mid -0.249642 0.249642)
							(end -0.1778 0.2794)
						)
						(arc
							(start 0.1778 0.2794)
							(mid 0.249642 0.249642)
							(end 0.2794 0.1778)
						)
						(arc
							(start 0.2794 -0.1778)
							(mid 0.249642 -0.249642)
							(end 0.1778 -0.2794)
						)
					)
					(width 0)
					(fill yes)
				)
			)
		)
	)
	(footprint ""
		(layer "F.Cu")
		(at 152.23236 -100.38588 90)
		(property "Reference" "R292"
			(at 0 0 90)
			(layer "F.SilkS")
			(hide yes)
			(effects
				(font
					(size 1.27 1.27)
				)
			)
		)
		(property "Value" "0R2J-2-GP"
			(at 0.064008 -3.993896 90)
			(unlocked yes)
			(layer "F.Fab")
			(hide yes)
			(effects
				(font
					(size 1.016 1.016)
					(thickness 0.1524)
				)
			)
		)
		(property "Device Type" "R402H16"
			(at 0.064008 -5.517896 90)
			(unlocked yes)
			(layer "F.Fab")
			(hide yes)
			(effects
				(font
					(size 1.016 1.016)
					(thickness 0.1524)
				)
			)
		)
		(duplicate_pad_numbers_are_jumpers no)
		(fp_line
			(start 0.508 -0.9398)
			(end -0.508 -0.9398)
			(stroke
				(width 0.1524)
				(type default)
			)
			(layer "F.SilkS")
		)
		(fp_line
			(start -0.508 -0.9398)
			(end -0.508 0.9398)
			(stroke
				(width 0.1524)
				(type default)
			)
			(layer "F.SilkS")
		)
		(fp_rect
			(start -0.508 0.9398)
			(end 0.508 -0.9398)
			(stroke
				(width 0)
				(type default)
			)
			(fill no)
			(layer "F.CrtYd")
		)
		(fp_rect
			(start -0.508 0.9398)
			(end 0.508 -0.9398)
			(stroke
				(width 0)
				(type default)
			)
			(fill no)
			(layer "F.Fab")
		)
		(pad "1" smd custom
			(at 0 -0.4445 90)
			(size 0.1397 0.1397)
			(layers "F.Cu" "F.Mask" "F.Paste")
			(net "UART_SDB_RX")
			(options
				(clearance outline)
				(anchor circle)
			)
			(primitives
				(gr_poly
					(pts
						(arc
							(start -0.1778 -0.2794)
							(mid -0.249642 -0.249642)
							(end -0.2794 -0.1778)
						)
						(arc
							(start -0.2794 0.1778)
							(mid -0.249642 0.249642)
							(end -0.1778 0.2794)
						)
						(arc
							(start 0.1778 0.2794)
							(mid 0.249642 0.249642)
							(end 0.2794 0.1778)
						)
						(arc
							(start 0.2794 -0.1778)
							(mid 0.249642 -0.249642)
							(end 0.1778 -0.2794)
						)
					)
					(width 0)
					(fill yes)
				)
			)
		)
		(pad "2" smd custom
			(at 0 0.4445 90)
			(size 0.1397 0.1397)
			(layers "F.Cu" "F.Mask" "F.Paste")
			(net "SAS_R_SDBRX")
			(options
				(clearance outline)
				(anchor circle)
			)
			(primitives
				(gr_poly
					(pts
						(arc
							(start -0.1778 -0.2794)
							(mid -0.249642 -0.249642)
							(end -0.2794 -0.1778)
						)
						(arc
							(start -0.2794 0.1778)
							(mid -0.249642 0.249642)
							(end -0.1778 0.2794)
						)
						(arc
							(start 0.1778 0.2794)
							(mid 0.249642 0.249642)
							(end 0.2794 0.1778)
						)
						(arc
							(start 0.2794 -0.1778)
							(mid 0.249642 -0.249642)
							(end 0.1778 -0.2794)
						)
					)
					(width 0)
					(fill yes)
				)
			)
		)
	)
	(footprint ""
		(layer "F.Cu")
		(at 166.233856 -55.208932)
		(property "Reference" "TP124"
			(at 0 0 0)
			(layer "F.SilkS")
			(hide yes)
			(effects
				(font
					(size 1.27 1.27)
				)
			)
		)
		(property "Value" "TPAD28-2-GP"
			(at -0.0127 -1.6637 0)
			(unlocked yes)
			(layer "F.Fab")
			(hide yes)
			(effects
				(font
					(size 1.016 1.016)
					(thickness 0.1524)
				)
			)
		)
		(property "Device Type" "TPAD28"
			(at -0.0127 -3.1877 0)
			(unlocked yes)
			(layer "F.Fab")
			(hide yes)
			(effects
				(font
					(size 1.016 1.016)
					(thickness 0.1524)
				)
			)
		)
		(duplicate_pad_numbers_are_jumpers no)
		(fp_poly
			(pts
				(arc
					(start 0.3556 0)
					(mid -0.3556 0)
					(end 0.3556 0)
				)
			)
			(stroke
				(width 0)
				(type default)
			)
			(fill no)
			(layer "F.CrtYd")
		)
		(fp_poly
			(pts
				(arc
					(start 0.6096 0)
					(mid -0.6096 0)
					(end 0.6096 0)
				)
			)
			(stroke
				(width 0)
				(type default)
			)
			(fill no)
			(layer "F.Fab")
		)
		(pad "1" smd circle
			(at 0 0)
			(size 0.7112 0.7112)
			(layers "F.Cu" "F.Mask" "F.Paste")
			(net "ICE1_TCK")
		)
	)
)
